# T6G (Grand Teton) — schematic netlist excerpt (pin names and nets, part order shuffled) for the footprints in the layout excerpt that follows; sources: Cadence DE-HDL packaged netlist, KiCad conversion of 04192023_DAF0TMB3IC0_F0TG_MB_C_brd_V02_OCP.brd

R1007  Q_RES  2K 1% EMPTY  pkg 0402LF  page 169 : A = P12V_AUX ; B = P12V_AUX_DSC_G1
PL6003  Q_INDUCTOR  BLM18SN220TN1D/8000MA IND  pkg SMLF  page 270 : \1\ = P12V_AUX ; \2\ = SW_P12V_AUX_P1V2_AUX_FLT

(kicad_pcb
	(version 20260206)
	(generator "pcbnew")
	(generator_version "10.0")
	(general
		(thickness 1.6)
		(legacy_teardrops no)
	)
	(paper "A4")
	(title_block
		(title "04192023_DAF0TMB3IC0_F0TG_MB_C_brd_V02_OCP.brd")
		(comment 1 "Grand Teton / footprints 2699-2700 of 8354")
	)
	(layers
		(0 "F.Cu" signal "TOP")
		(4 "In1.Cu" signal "GND")
		(6 "In2.Cu" signal "IN1")
		(8 "In3.Cu" signal "GND1")
		(10 "In4.Cu" signal "IN2")
		(12 "In5.Cu" signal "GND2")
		(14 "In6.Cu" signal "IN3")
		(16 "In7.Cu" signal "GND3")
		(18 "In8.Cu" signal "VCC")
		(20 "In9.Cu" signal "VCC1")
		(22 "In10.Cu" signal "GND4")
		(24 "In11.Cu" signal "IN4")
		(26 "In12.Cu" signal "GND5")
		(28 "In13.Cu" signal "IN5")
		(30 "In14.Cu" signal "GND6")
		(32 "In15.Cu" signal "IN6")
		(34 "In16.Cu" signal "GND7")
		(2 "B.Cu" signal "BOTTOM")
		(9 "F.Adhes" user "F.Adhesive")
		(11 "B.Adhes" user "B.Adhesive")
		(13 "F.Paste" user "Package Geometry/Pastemask Top")
		(15 "B.Paste" user "Package Geometry/Pastemask Bottom")
		(5 "F.SilkS" user "Ref Des/Silkscreen Top")
		(7 "B.SilkS" user "Ref Des/Silkscreen Bottom")
		(1 "F.Mask" user "Board Geometry/Soldermask Top")
		(3 "B.Mask" user "Board Geometry/Soldermask Bottom")
		(17 "Dwgs.User" user "User.Drawings")
		(19 "Cmts.User" user "User.Comments")
		(21 "Eco1.User" user "User.Eco1")
		(23 "Eco2.User" user "User.Eco2")
		(25 "Edge.Cuts" user "Board Geometry/Outline")
		(27 "Margin" user)
		(31 "F.CrtYd" user "Package Geometry/Place Bound Top")
		(29 "B.CrtYd" user "Package Geometry/Place Bound Bottom")
		(35 "F.Fab" user "Ref Des/Assembly Top")
		(33 "B.Fab" user "Ref Des/Assembly Bottom")
	)
	(footprint ""
		(layer "F.Cu")
		(at 115.815872 -73.954132 90)
		(property "Reference" "PL6003"
			(at 0 0 90)
			(layer "F.SilkS")
			(hide yes)
			(effects
				(font
					(size 1.27 1.27)
				)
			)
		)
		(property "Value" ""
			(at 0 0 90)
			(layer "F.Fab")
			(effects
				(font
					(size 1.27 1.27)
				)
			)
		)
		(duplicate_pad_numbers_are_jumpers no)
		(fp_line
			(start -1.27 -0.5842)
			(end 1.27 -0.5842)
			(stroke
				(width 0.1524)
				(type default)
			)
			(layer "F.SilkS")
		)
		(fp_line
			(start -1.27 -0.5588)
			(end -1.27 -0.5842)
			(stroke
				(width 0.1524)
				(type default)
			)
			(layer "F.SilkS")
		)
		(fp_line
			(start 1.27 0.5842)
			(end 1.27 -0.5842)
			(stroke
				(width 0.1524)
				(type default)
			)
			(layer "F.SilkS")
		)
		(fp_line
			(start 1.27 0.5842)
			(end -1.27 0.5842)
			(stroke
				(width 0.1524)
				(type default)
			)
			(layer "F.SilkS")
		)
		(fp_line
			(start -1.27 0.5842)
			(end -1.27 -0.5842)
			(stroke
				(width 0.1524)
				(type default)
			)
			(layer "F.SilkS")
		)
		(fp_line
			(start 0.9144 -0.508)
			(end 0.9144 -0.406654)
			(stroke
				(width 0.1)
				(type default)
			)
			(layer "F.Fab")
		)
		(fp_line
			(start -0.9144 -0.508)
			(end 0.9144 -0.508)
			(stroke
				(width 0.1)
				(type default)
			)
			(layer "F.Fab")
		)
		(fp_line
			(start 1.1938 -0.406654)
			(end 1.1938 0.4064)
			(stroke
				(width 0.1)
				(type default)
			)
			(layer "F.Fab")
		)
		(fp_line
			(start 0.9144 -0.406654)
			(end 1.1938 -0.406654)
			(stroke
				(width 0.1)
				(type default)
			)
			(layer "F.Fab")
		)
		(fp_line
			(start -0.9144 -0.406654)
			(end -0.9144 -0.508)
			(stroke
				(width 0.1)
				(type default)
			)
			(layer "F.Fab")
		)
		(fp_line
			(start -1.194308 -0.406654)
			(end -0.9144 -0.406654)
			(stroke
				(width 0.1)
				(type default)
			)
			(layer "F.Fab")
		)
		(fp_line
			(start 1.1938 0.4064)
			(end 0.9144 0.4064)
			(stroke
				(width 0.1)
				(type default)
			)
			(layer "F.Fab")
		)
		(fp_line
			(start 0.9144 0.4064)
			(end 0.9144 0.508)
			(stroke
				(width 0.1)
				(type default)
			)
			(layer "F.Fab")
		)
		(fp_line
			(start -0.9144 0.406654)
			(end -1.194308 0.406654)
			(stroke
				(width 0.1)
				(type default)
			)
			(layer "F.Fab")
		)
		(fp_line
			(start -1.194308 0.406654)
			(end -1.194308 -0.406654)
			(stroke
				(width 0.1)
				(type default)
			)
			(layer "F.Fab")
		)
		(fp_line
			(start 0.9144 0.508)
			(end -0.9144 0.508)
			(stroke
				(width 0.1)
				(type default)
			)
			(layer "F.Fab")
		)
		(fp_line
			(start -0.9144 0.508)
			(end -0.9144 0.406654)
			(stroke
				(width 0.1)
				(type default)
			)
			(layer "F.Fab")
		)
		(pad "1" smd rect
			(at -0.7366 0)
			(size 0.7112 0.8128)
			(layers "F.Cu" "F.Mask" "F.Paste")
			(net "P12V_AUX")
		)
		(pad "2" smd rect
			(at 0.7366 0)
			(size 0.7112 0.8128)
			(layers "F.Cu" "F.Mask" "F.Paste")
			(net "SW_P12V_AUX_P1V2_AUX_FLT")
		)
	)
	(footprint ""
		(layer "F.Cu")
		(at 35.65144 -108.09732 -90)
		(property "Reference" "R1007"
			(at 0 0 270)
			(layer "F.SilkS")
			(hide yes)
			(effects
				(font
					(size 1.27 1.27)
				)
			)
		)
		(property "Value" ""
			(at 0 0 270)
			(layer "F.Fab")
			(effects
				(font
					(size 1.27 1.27)
				)
			)
		)
		(duplicate_pad_numbers_are_jumpers no)
		(fp_line
			(start -0.7874 0.4064)
			(end -0.7874 -0.4064)
			(stroke
				(width 0.1524)
				(type default)
			)
			(layer "F.SilkS")
		)
		(fp_line
			(start 0.7874 0.4064)
			(end -0.7874 0.4064)
			(stroke
				(width 0.1524)
				(type default)
			)
			(layer "F.SilkS")
		)
		(fp_line
			(start -0.7874 -0.4064)
			(end 0.7874 -0.4064)
			(stroke
				(width 0.1524)
				(type default)
			)
			(layer "F.SilkS")
		)
		(fp_line
			(start 0.7874 -0.4064)
			(end 0.7874 0.4064)
			(stroke
				(width 0.1524)
				(type default)
			)
			(layer "F.SilkS")
		)
		(fp_line
			(start -0.67945 0.3048)
			(end -0.67945 -0.305054)
			(stroke
				(width 0.1)
				(type default)
			)
			(layer "F.Fab")
		)
		(fp_line
			(start -0.12065 0.3048)
			(end -0.67945 0.3048)
			(stroke
				(width 0.1)
				(type default)
			)
			(layer "F.Fab")
		)
		(fp_line
			(start 0.120396 0.3048)
			(end 0.120396 0.2794)
			(stroke
				(width 0.1)
				(type default)
			)
			(layer "F.Fab")
		)
		(fp_line
			(start 0.67945 0.3048)
			(end 0.120396 0.3048)
			(stroke
				(width 0.1)
				(type default)
			)
			(layer "F.Fab")
		)
		(fp_line
			(start -0.12065 0.2794)
			(end -0.12065 0.3048)
			(stroke
				(width 0.1)
				(type default)
			)
			(layer "F.Fab")
		)
		(fp_line
			(start 0.120396 0.2794)
			(end -0.12065 0.2794)
			(stroke
				(width 0.1)
				(type default)
			)
			(layer "F.Fab")
		)
		(fp_line
			(start -0.12065 -0.2794)
			(end 0.12065 -0.2794)
			(stroke
				(width 0.1)
				(type default)
			)
			(layer "F.Fab")
		)
		(fp_line
			(start 0.12065 -0.2794)
			(end 0.12065 -0.3048)
			(stroke
				(width 0.1)
				(type default)
			)
			(layer "F.Fab")
		)
		(fp_line
			(start 0.12065 -0.3048)
			(end 0.67945 -0.3048)
			(stroke
				(width 0.1)
				(type default)
			)
			(layer "F.Fab")
		)
		(fp_line
			(start 0.67945 -0.3048)
			(end 0.67945 0.3048)
			(stroke
				(width 0.1)
				(type default)
			)
			(layer "F.Fab")
		)
		(fp_line
			(start -0.67945 -0.305054)
			(end -0.12065 -0.305054)
			(stroke
				(width 0.1)
				(type default)
			)
			(layer "F.Fab")
		)
		(fp_line
			(start -0.12065 -0.305054)
			(end -0.12065 -0.2794)
			(stroke
				(width 0.1)
				(type default)
			)
			(layer "F.Fab")
		)
		(pad "1" smd circle
			(at -0.40005 0 270)
			(size 0 0)
			(layers "F.Cu" "F.Mask" "F.Paste")
			(net "P12V_AUX")
		)
		(pad "2" smd circle
			(at 0.40005 0 270)
			(size 0 0)
			(layers "F.Cu" "F.Mask" "F.Paste")
			(net "P12V_AUX_DSC_G1")
		)
	)
)
